# SCM (Grand Teton) — schematic netlist excerpt (pin names and nets, part order shuffled) for the footprints in the layout excerpt that follows; sources: Cadence DE-HDL packaged netlist, KiCad conversion of 12092022_DA0F0TMDCD0_F0T_Management_Board_D_brd_V3_OCP.brd

X11  TP_TDR_4P_FTS  TP_TDR_4P_DIP EMPTY  pkg TH  page 60
  S1  = TDR_DIFF_85_IN4_DN
  P1  = GND_P1
  P2  = GND_P1
  S2  = TDR_DIFF_85_IN4_DP

R43  Q_RES  220 1% CHIP  pkg 0402LF  page 49 : A = ID_LED_P3V3_AUX ; B = P3V3_AUX

(kicad_pcb
	(version 20260206)
	(generator "pcbnew")
	(generator_version "10.0")
	(general
		(thickness 1.6)
		(legacy_teardrops no)
	)
	(paper "A4")
	(title_block
		(title "12092022_DA0F0TMDCD0_F0T_Management_Board_D_brd_V3_OCP.brd")
		(comment 1 "Grand Teton / footprints 120-121 of 1440")
	)
	(layers
		(0 "F.Cu" signal "TOP")
		(4 "In1.Cu" signal "GND")
		(6 "In2.Cu" signal "IN1")
		(8 "In3.Cu" signal "GND1")
		(10 "In4.Cu" signal "IN2")
		(12 "In5.Cu" signal "VCC")
		(14 "In6.Cu" signal "VCC1")
		(16 "In7.Cu" signal "IN3")
		(18 "In8.Cu" signal "GND2")
		(20 "In9.Cu" signal "IN4")
		(22 "In10.Cu" signal "GND3")
		(2 "B.Cu" signal "BOTTOM")
		(9 "F.Adhes" user "F.Adhesive")
		(11 "B.Adhes" user "B.Adhesive")
		(13 "F.Paste" user "Package Geometry/Pastemask Top")
		(15 "B.Paste" user "Package Geometry/Pastemask Bottom")
		(5 "F.SilkS" user "Ref Des/Silkscreen Top")
		(7 "B.SilkS" user "Ref Des/Silkscreen Bottom")
		(1 "F.Mask" user "Board Geometry/Soldermask Top")
		(3 "B.Mask" user "Board Geometry/Soldermask Bottom")
		(17 "Dwgs.User" user "User.Drawings")
		(19 "Cmts.User" user "User.Comments")
		(21 "Eco1.User" user "User.Eco1")
		(23 "Eco2.User" user "User.Eco2")
		(25 "Edge.Cuts" user "Board Geometry/Outline")
		(27 "Margin" user)
		(31 "F.CrtYd" user "Package Geometry/Place Bound Top")
		(29 "B.CrtYd" user "Package Geometry/Place Bound Bottom")
		(35 "F.Fab" user "Ref Des/Assembly Top")
		(33 "B.Fab" user "Ref Des/Assembly Bottom")
	)
	(footprint ""
		(layer "F.Cu")
		(at 30.607 -10.287 90)
		(property "Reference" "R43"
			(at 0 0 90)
			(layer "F.SilkS")
			(hide yes)
			(effects
				(font
					(size 1.27 1.27)
				)
			)
		)
		(property "Value" ""
			(at 0 0 90)
			(layer "F.Fab")
			(effects
				(font
					(size 1.27 1.27)
				)
			)
		)
		(duplicate_pad_numbers_are_jumpers no)
		(fp_line
			(start 0.7874 -0.4064)
			(end 0.7874 0.4064)
			(stroke
				(width 0.1524)
				(type default)
			)
			(layer "F.SilkS")
		)
		(fp_line
			(start -0.7874 -0.4064)
			(end 0.7874 -0.4064)
			(stroke
				(width 0.1524)
				(type default)
			)
			(layer "F.SilkS")
		)
		(fp_line
			(start 0.7874 0.4064)
			(end -0.7874 0.4064)
			(stroke
				(width 0.1524)
				(type default)
			)
			(layer "F.SilkS")
		)
		(fp_line
			(start -0.7874 0.4064)
			(end -0.7874 -0.4064)
			(stroke
				(width 0.1524)
				(type default)
			)
			(layer "F.SilkS")
		)
		(fp_line
			(start -0.12065 -0.305054)
			(end -0.12065 -0.2794)
			(stroke
				(width 0.1)
				(type default)
			)
			(layer "F.Fab")
		)
		(fp_line
			(start -0.67945 -0.305054)
			(end -0.12065 -0.305054)
			(stroke
				(width 0.1)
				(type default)
			)
			(layer "F.Fab")
		)
		(fp_line
			(start 0.67945 -0.3048)
			(end 0.67945 0.3048)
			(stroke
				(width 0.1)
				(type default)
			)
			(layer "F.Fab")
		)
		(fp_line
			(start 0.12065 -0.3048)
			(end 0.67945 -0.3048)
			(stroke
				(width 0.1)
				(type default)
			)
			(layer "F.Fab")
		)
		(fp_line
			(start 0.12065 -0.2794)
			(end 0.12065 -0.3048)
			(stroke
				(width 0.1)
				(type default)
			)
			(layer "F.Fab")
		)
		(fp_line
			(start -0.12065 -0.2794)
			(end 0.12065 -0.2794)
			(stroke
				(width 0.1)
				(type default)
			)
			(layer "F.Fab")
		)
		(fp_line
			(start 0.120396 0.2794)
			(end -0.12065 0.2794)
			(stroke
				(width 0.1)
				(type default)
			)
			(layer "F.Fab")
		)
		(fp_line
			(start -0.12065 0.2794)
			(end -0.12065 0.3048)
			(stroke
				(width 0.1)
				(type default)
			)
			(layer "F.Fab")
		)
		(fp_line
			(start 0.67945 0.3048)
			(end 0.120396 0.3048)
			(stroke
				(width 0.1)
				(type default)
			)
			(layer "F.Fab")
		)
		(fp_line
			(start 0.120396 0.3048)
			(end 0.120396 0.2794)
			(stroke
				(width 0.1)
				(type default)
			)
			(layer "F.Fab")
		)
		(fp_line
			(start -0.12065 0.3048)
			(end -0.67945 0.3048)
			(stroke
				(width 0.1)
				(type default)
			)
			(layer "F.Fab")
		)
		(fp_line
			(start -0.67945 0.3048)
			(end -0.67945 -0.305054)
			(stroke
				(width 0.1)
				(type default)
			)
			(layer "F.Fab")
		)
		(pad "1" smd circle
			(at -0.40005 0 90)
			(size 0 0)
			(layers "F.Cu" "F.Mask" "F.Paste")
			(net "ID_LED_P3V3_AUX")
		)
		(pad "2" smd circle
			(at 0.40005 0 90)
			(size 0 0)
			(layers "F.Cu" "F.Mask" "F.Paste")
			(net "P3V3_AUX")
		)
	)
	(footprint ""
		(layer "F.Cu")
		(at 114.554 -32.004 -90)
		(property "Reference" "X11"
			(at 2.0955 -2.83337 90)
			(unlocked yes)
			(layer "F.SilkS")
			(effects
				(font
					(size 0.7874 0.5842)
					(thickness 0.1524)
				)
				(justify left)
			)
		)
		(property "Value" ""
			(at 0 0 270)
			(layer "F.Fab")
			(effects
				(font
					(size 1.27 1.27)
				)
			)
		)
		(property "Device Type" "TP_TDR_4P_FTS_TH-TP_TDR_4P_DIPA"
			(at 1.30175 1.27 0)
			(unlocked yes)
			(layer "F.Fab")
			(hide yes)
			(effects
				(font
					(size 0.635 0.4064)
					(thickness 0.1524)
				)
			)
		)
		(property "User Part Number" "N_A"
			(at 1.30175 1.27 0)
			(unlocked yes)
			(layer "Cmts.User")
			(hide yes)
			(effects
				(font
					(size 0.635 0.4064)
					(thickness 0.1524)
				)
			)
		)
		(duplicate_pad_numbers_are_jumpers no)
		(fp_line
			(start 0 3.81)
			(end 2.54 3.81)
			(stroke
				(width 0.1524)
				(type default)
			)
			(layer "F.SilkS")
		)
		(fp_line
			(start 2.54 3.81)
			(end 2.54 3.6703)
			(stroke
				(width 0.1524)
				(type default)
			)
			(layer "F.SilkS")
		)
		(fp_line
			(start 0 3.175)
			(end 0 3.81)
			(stroke
				(width 0.1524)
				(type default)
			)
			(layer "F.SilkS")
		)
		(fp_line
			(start 2.54 1.4097)
			(end 2.54 1.1303)
			(stroke
				(width 0.1524)
				(type default)
			)
			(layer "F.SilkS")
		)
		(fp_line
			(start 0 0.635)
			(end 0 1.905)
			(stroke
				(width 0.1524)
				(type default)
			)
			(layer "F.SilkS")
		)
		(fp_line
			(start 2.54 -1.1303)
			(end 2.54 -1.27)
			(stroke
				(width 0.1524)
				(type default)
			)
			(layer "F.SilkS")
		)
		(fp_line
			(start 0 -1.27)
			(end 0 -0.635)
			(stroke
				(width 0.1524)
				(type default)
			)
			(layer "F.SilkS")
		)
		(fp_line
			(start 2.54 -1.27)
			(end 0 -1.27)
			(stroke
				(width 0.1524)
				(type default)
			)
			(layer "F.SilkS")
		)
		(fp_poly
			(pts
				(xy -0.761746 0) (xy -2.285746 -0.762) (xy -2.285746 0.762)
			)
			(stroke
				(width 0)
				(type default)
			)
			(fill yes)
			(layer "F.SilkS")
		)
		(fp_line
			(start 0 3.81)
			(end 2.54 3.81)
			(stroke
				(width 0.1)
				(type default)
			)
			(layer "F.Fab")
		)
		(fp_line
			(start 2.54 3.81)
			(end 2.54 -1.27)
			(stroke
				(width 0.1)
				(type default)
			)
			(layer "F.Fab")
		)
		(fp_line
			(start 0 -1.27)
			(end 0 3.81)
			(stroke
				(width 0.1)
				(type default)
			)
			(layer "F.Fab")
		)
		(fp_line
			(start 2.54 -1.27)
			(end 0 -1.27)
			(stroke
				(width 0.1)
				(type default)
			)
			(layer "F.Fab")
		)
		(fp_poly
			(pts
				(xy -0.761746 0) (xy -2.285746 -0.762) (xy -2.285746 0.762)
			)
			(stroke
				(width 0)
				(type default)
			)
			(fill yes)
			(layer "F.Fab")
		)
		(pad "1" thru_hole circle
			(at 0 0 270)
			(size 1.0033 1.0033)
			(drill 0.249936)
			(layers "*.Cu" "*.Mask")
			(remove_unused_layers no)
			(net "TDR_DIFF_85_IN4_DN")
			(clearance 0.10795)
			(thermal_gap 0.10795)
			(padstack
				(mode front_inner_back)
				(layer "Inner"
					(shape circle)
					(size 0.8001 0.8001)
					(clearance 0.1524)
				)
				(layer "B.Cu"
					(shape circle)
					(size 1.0033 1.0033)
					(clearance 0.10795)
				)
			)
		)
		(pad "2" thru_hole circle
			(at 2.54 0 270)
			(size 1.9939 1.9939)
			(drill 0.249936)
			(layers "*.Cu" "*.Mask")
			(remove_unused_layers no)
			(net "GND_P1")
			(clearance 0.10795)
			(thermal_gap 0.10795)
			(padstack
				(mode front_inner_back)
				(layer "Inner"
					(shape circle)
					(size 0.8001 0.8001)
					(clearance 0.1524)
				)
				(layer "B.Cu"
					(shape circle)
					(size 1.9939 1.9939)
					(clearance 0.10795)
				)
			)
		)
		(pad "3" thru_hole circle
			(at 2.54 2.54 270)
			(size 1.9939 1.9939)
			(drill 0.249936)
			(layers "*.Cu" "*.Mask")
			(remove_unused_layers no)
			(net "GND_P1")
			(clearance 0.10795)
			(thermal_gap 0.10795)
			(padstack
				(mode front_inner_back)
				(layer "Inner"
					(shape circle)
					(size 0.8001 0.8001)
					(clearance 0.1524)
				)
				(layer "B.Cu"
					(shape circle)
					(size 1.9939 1.9939)
					(clearance 0.10795)
				)
			)
		)
		(pad "4" thru_hole circle
			(at 0 2.54 270)
			(size 1.0033 1.0033)
			(drill 0.249936)
			(layers "*.Cu" "*.Mask")
			(remove_unused_layers no)
			(net "TDR_DIFF_85_IN4_DP")
			(clearance 0.10795)
			(thermal_gap 0.10795)
			(padstack
				(mode front_inner_back)
				(layer "Inner"
					(shape circle)
					(size 0.8001 0.8001)
					(clearance 0.1524)
				)
				(layer "B.Cu"
					(shape circle)
					(size 1.0033 1.0033)
					(clearance 0.10795)
				)
			)
		)
	)
)
